(kicad_pcb
	(version 20260206)
	(generator "pcbnew")
	(generator_version "10.0")
	(general
		(thickness 1.6)
		(legacy_teardrops no)
	)
	(paper "A4")
	(title_block
		(title "04192023_DAF0TMB3IC0_F0TG_MB_C_brd_V02_OCP.brd")
		(comment 1 "Grand Teton / footprints 1909-1914 of 8354")
	)
	(layers
		(0 "F.Cu" signal "TOP")
		(4 "In1.Cu" signal "GND")
		(6 "In2.Cu" signal "IN1")
		(8 "In3.Cu" signal "GND1")
		(10 "In4.Cu" signal "IN2")
		(12 "In5.Cu" signal "GND2")
		(14 "In6.Cu" signal "IN3")
		(16 "In7.Cu" signal "GND3")
		(18 "In8.Cu" signal "VCC")
		(20 "In9.Cu" signal "VCC1")
		(22 "In10.Cu" signal "GND4")
		(24 "In11.Cu" signal "IN4")
		(26 "In12.Cu" signal "GND5")
		(28 "In13.Cu" signal "IN5")
		(30 "In14.Cu" signal "GND6")
		(32 "In15.Cu" signal "IN6")
		(34 "In16.Cu" signal "GND7")
		(2 "B.Cu" signal "BOTTOM")
		(9 "F.Adhes" user "F.Adhesive")
		(11 "B.Adhes" user "B.Adhesive")
		(13 "F.Paste" user "Package Geometry/Pastemask Top")
		(15 "B.Paste" user "Package Geometry/Pastemask Bottom")
		(5 "F.SilkS" user "Ref Des/Silkscreen Top")
		(7 "B.SilkS" user "Ref Des/Silkscreen Bottom")
		(1 "F.Mask" user "Board Geometry/Soldermask Top")
		(3 "B.Mask" user "Board Geometry/Soldermask Bottom")
		(17 "Dwgs.User" user "User.Drawings")
		(19 "Cmts.User" user "User.Comments")
		(21 "Eco1.User" user "User.Eco1")
		(23 "Eco2.User" user "User.Eco2")
		(25 "Edge.Cuts" user "Board Geometry/Outline")
		(27 "Margin" user)
		(31 "F.CrtYd" user "Package Geometry/Place Bound Top")
		(29 "B.CrtYd" user "Package Geometry/Place Bound Bottom")
		(35 "F.Fab" user "Ref Des/Assembly Top")
		(33 "B.Fab" user "Ref Des/Assembly Bottom")
	)
	(footprint ""
		(layer "F.Cu")
		(at 271.295876 -418.97173 90)
		(property "Reference" "R2585"
			(at 0 0 90)
			(layer "F.SilkS")
			(hide yes)
			(effects
				(font
					(size 1.27 1.27)
				)
			)
		)
		(property "Value" ""
			(at 0 0 90)
			(layer "F.Fab")
			(effects
				(font
					(size 1.27 1.27)
				)
			)
		)
		(duplicate_pad_numbers_are_jumpers no)
		(fp_line
			(start 0.7874 -0.4064)
			(end 0.7874 0.4064)
			(stroke
				(width 0.1524)
				(type default)
			)
			(layer "F.SilkS")
		)
		(fp_line
			(start -0.7874 -0.4064)
			(end 0.7874 -0.4064)
			(stroke
				(width 0.1524)
				(type default)
			)
			(layer "F.SilkS")
		)
		(fp_line
			(start 0.7874 0.4064)
			(end -0.7874 0.4064)
			(stroke
				(width 0.1524)
				(type default)
			)
			(layer "F.SilkS")
		)
		(fp_line
			(start -0.7874 0.4064)
			(end -0.7874 -0.4064)
			(stroke
				(width 0.1524)
				(type default)
			)
			(layer "F.SilkS")
		)
		(fp_line
			(start -0.12065 -0.305054)
			(end -0.12065 -0.2794)
			(stroke
				(width 0.1)
				(type default)
			)
			(layer "F.Fab")
		)
		(fp_line
			(start -0.67945 -0.305054)
			(end -0.12065 -0.305054)
			(stroke
				(width 0.1)
				(type default)
			)
			(layer "F.Fab")
		)
		(fp_line
			(start 0.67945 -0.3048)
			(end 0.67945 0.3048)
			(stroke
				(width 0.1)
				(type default)
			)
			(layer "F.Fab")
		)
		(fp_line
			(start 0.12065 -0.3048)
			(end 0.67945 -0.3048)
			(stroke
				(width 0.1)
				(type default)
			)
			(layer "F.Fab")
		)
		(fp_line
			(start 0.12065 -0.2794)
			(end 0.12065 -0.3048)
			(stroke
				(width 0.1)
				(type default)
			)
			(layer "F.Fab")
		)
		(fp_line
			(start -0.12065 -0.2794)
			(end 0.12065 -0.2794)
			(stroke
				(width 0.1)
				(type default)
			)
			(layer "F.Fab")
		)
		(fp_line
			(start 0.120396 0.2794)
			(end -0.12065 0.2794)
			(stroke
				(width 0.1)
				(type default)
			)
			(layer "F.Fab")
		)
		(fp_line
			(start -0.12065 0.2794)
			(end -0.12065 0.3048)
			(stroke
				(width 0.1)
				(type default)
			)
			(layer "F.Fab")
		)
		(fp_line
			(start 0.67945 0.3048)
			(end 0.120396 0.3048)
			(stroke
				(width 0.1)
				(type default)
			)
			(layer "F.Fab")
		)
		(fp_line
			(start 0.120396 0.3048)
			(end 0.120396 0.2794)
			(stroke
				(width 0.1)
				(type default)
			)
			(layer "F.Fab")
		)
		(fp_line
			(start -0.12065 0.3048)
			(end -0.67945 0.3048)
			(stroke
				(width 0.1)
				(type default)
			)
			(layer "F.Fab")
		)
		(fp_line
			(start -0.67945 0.3048)
			(end -0.67945 -0.305054)
			(stroke
				(width 0.1)
				(type default)
			)
			(layer "F.Fab")
		)
		(pad "1" smd circle
			(at -0.40005 0 90)
			(size 0 0)
			(layers "F.Cu" "F.Mask" "F.Paste")
			(net "HSC_EN")
		)
		(pad "2" smd circle
			(at 0.40005 0 90)
			(size 0 0)
			(layers "F.Cu" "F.Mask" "F.Paste")
			(net "GND")
		)
	)
	(footprint ""
		(layer "F.Cu")
		(at 171.196 -115.280948)
		(property "Reference" "R56"
			(at 0 0 0)
			(layer "F.SilkS")
			(hide yes)
			(effects
				(font
					(size 1.27 1.27)
				)
			)
		)
		(property "Value" ""
			(at 0 0 0)
			(layer "F.Fab")
			(effects
				(font
					(size 1.27 1.27)
				)
			)
		)
		(duplicate_pad_numbers_are_jumpers no)
		(fp_line
			(start -0.7874 -0.4064)
			(end 0.7874 -0.4064)
			(stroke
				(width 0.1524)
				(type default)
			)
			(layer "F.SilkS")
		)
		(fp_line
			(start -0.7874 0.4064)
			(end -0.7874 -0.4064)
			(stroke
				(width 0.1524)
				(type default)
			)
			(layer "F.SilkS")
		)
		(fp_line
			(start 0.7874 -0.4064)
			(end 0.7874 0.4064)
			(stroke
				(width 0.1524)
				(type default)
			)
			(layer "F.SilkS")
		)
		(fp_line
			(start 0.7874 0.4064)
			(end -0.7874 0.4064)
			(stroke
				(width 0.1524)
				(type default)
			)
			(layer "F.SilkS")
		)
		(fp_line
			(start -0.67945 -0.305054)
			(end -0.12065 -0.305054)
			(stroke
				(width 0.1)
				(type default)
			)
			(layer "F.Fab")
		)
		(fp_line
			(start -0.67945 0.3048)
			(end -0.67945 -0.305054)
			(stroke
				(width 0.1)
				(type default)
			)
			(layer "F.Fab")
		)
		(fp_line
			(start -0.12065 -0.305054)
			(end -0.12065 -0.2794)
			(stroke
				(width 0.1)
				(type default)
			)
			(layer "F.Fab")
		)
		(fp_line
			(start -0.12065 -0.2794)
			(end 0.12065 -0.2794)
			(stroke
				(width 0.1)
				(type default)
			)
			(layer "F.Fab")
		)
		(fp_line
			(start -0.12065 0.2794)
			(end -0.12065 0.3048)
			(stroke
				(width 0.1)
				(type default)
			)
			(layer "F.Fab")
		)
		(fp_line
			(start -0.12065 0.3048)
			(end -0.67945 0.3048)
			(stroke
				(width 0.1)
				(type default)
			)
			(layer "F.Fab")
		)
		(fp_line
			(start 0.120396 0.2794)
			(end -0.12065 0.2794)
			(stroke
				(width 0.1)
				(type default)
			)
			(layer "F.Fab")
		)
		(fp_line
			(start 0.120396 0.3048)
			(end 0.120396 0.2794)
			(stroke
				(width 0.1)
				(type default)
			)
			(layer "F.Fab")
		)
		(fp_line
			(start 0.12065 -0.3048)
			(end 0.67945 -0.3048)
			(stroke
				(width 0.1)
				(type default)
			)
			(layer "F.Fab")
		)
		(fp_line
			(start 0.12065 -0.2794)
			(end 0.12065 -0.3048)
			(stroke
				(width 0.1)
				(type default)
			)
			(layer "F.Fab")
		)
		(fp_line
			(start 0.67945 -0.3048)
			(end 0.67945 0.3048)
			(stroke
				(width 0.1)
				(type default)
			)
			(layer "F.Fab")
		)
		(fp_line
			(start 0.67945 0.3048)
			(end 0.120396 0.3048)
			(stroke
				(width 0.1)
				(type default)
			)
			(layer "F.Fab")
		)
		(pad "1" smd circle
			(at -0.40005 0)
			(size 0 0)
			(layers "F.Cu" "F.Mask" "F.Paste")
			(net "SMB_1_PLD_3V3AUX_SDA_R1")
		)
		(pad "2" smd circle
			(at 0.40005 0)
			(size 0 0)
			(layers "F.Cu" "F.Mask" "F.Paste")
			(net "SMB_1_PLD_3V3AUX_SDA_R2")
		)
	)
	(footprint ""
		(layer "F.Cu")
		(at 33.617662 -419.249098 90)
		(property "Reference" "R3275"
			(at 0 0 90)
			(layer "F.SilkS")
			(hide yes)
			(effects
				(font
					(size 1.27 1.27)
				)
			)
		)
		(property "Value" ""
			(at 0 0 90)
			(layer "F.Fab")
			(effects
				(font
					(size 1.27 1.27)
				)
			)
		)
		(duplicate_pad_numbers_are_jumpers no)
		(fp_line
			(start 0.7874 -0.4064)
			(end 0.7874 0.4064)
			(stroke
				(width 0.1524)
				(type default)
			)
			(layer "F.SilkS")
		)
		(fp_line
			(start -0.7874 -0.4064)
			(end 0.7874 -0.4064)
			(stroke
				(width 0.1524)
				(type default)
			)
			(layer "F.SilkS")
		)
		(fp_line
			(start 0.7874 0.4064)
			(end -0.7874 0.4064)
			(stroke
				(width 0.1524)
				(type default)
			)
			(layer "F.SilkS")
		)
		(fp_line
			(start -0.7874 0.4064)
			(end -0.7874 -0.4064)
			(stroke
				(width 0.1524)
				(type default)
			)
			(layer "F.SilkS")
		)
		(fp_line
			(start -0.12065 -0.305054)
			(end -0.12065 -0.2794)
			(stroke
				(width 0.1)
				(type default)
			)
			(layer "F.Fab")
		)
		(fp_line
			(start -0.67945 -0.305054)
			(end -0.12065 -0.305054)
			(stroke
				(width 0.1)
				(type default)
			)
			(layer "F.Fab")
		)
		(fp_line
			(start 0.67945 -0.3048)
			(end 0.67945 0.3048)
			(stroke
				(width 0.1)
				(type default)
			)
			(layer "F.Fab")
		)
		(fp_line
			(start 0.12065 -0.3048)
			(end 0.67945 -0.3048)
			(stroke
				(width 0.1)
				(type default)
			)
			(layer "F.Fab")
		)
		(fp_line
			(start 0.12065 -0.2794)
			(end 0.12065 -0.3048)
			(stroke
				(width 0.1)
				(type default)
			)
			(layer "F.Fab")
		)
		(fp_line
			(start -0.12065 -0.2794)
			(end 0.12065 -0.2794)
			(stroke
				(width 0.1)
				(type default)
			)
			(layer "F.Fab")
		)
		(fp_line
			(start 0.120396 0.2794)
			(end -0.12065 0.2794)
			(stroke
				(width 0.1)
				(type default)
			)
			(layer "F.Fab")
		)
		(fp_line
			(start -0.12065 0.2794)
			(end -0.12065 0.3048)
			(stroke
				(width 0.1)
				(type default)
			)
			(layer "F.Fab")
		)
		(fp_line
			(start 0.67945 0.3048)
			(end 0.120396 0.3048)
			(stroke
				(width 0.1)
				(type default)
			)
			(layer "F.Fab")
		)
		(fp_line
			(start 0.120396 0.3048)
			(end 0.120396 0.2794)
			(stroke
				(width 0.1)
				(type default)
			)
			(layer "F.Fab")
		)
		(fp_line
			(start -0.12065 0.3048)
			(end -0.67945 0.3048)
			(stroke
				(width 0.1)
				(type default)
			)
			(layer "F.Fab")
		)
		(fp_line
			(start -0.67945 0.3048)
			(end -0.67945 -0.305054)
			(stroke
				(width 0.1)
				(type default)
			)
			(layer "F.Fab")
		)
		(pad "1" smd circle
			(at -0.40005 0 90)
			(size 0 0)
			(layers "F.Cu" "F.Mask" "F.Paste")
			(net "P3V3_AUX")
		)
		(pad "2" smd circle
			(at 0.40005 0 90)
			(size 0 0)
			(layers "F.Cu" "F.Mask" "F.Paste")
			(net "FM_P2E_FGA")
		)
	)
	(footprint ""
		(layer "F.Cu")
		(at 243.37137 -291.761926)
		(property "Reference" "PU6500"
			(at 0.786384 -3.70332 0)
			(unlocked yes)
			(layer "F.SilkS")
			(effects
				(font
					(size 0.7874 0.5842)
					(thickness 0.1524)
				)
				(justify left)
			)
		)
		(property "Value" ""
			(at 0 0 0)
			(layer "F.Fab")
			(effects
				(font
					(size 1.27 1.27)
				)
			)
		)
		(duplicate_pad_numbers_are_jumpers no)
		(fp_line
			(start -1.549908 -2.050034)
			(end -1.549908 -1.9812)
			(stroke
				(width 0.1524)
				(type default)
			)
			(layer "F.SilkS")
		)
		(fp_line
			(start -1.549908 1.9812)
			(end -1.549908 2.050034)
			(stroke
				(width 0.1524)
				(type default)
			)
			(layer "F.SilkS")
		)
		(fp_line
			(start -1.549908 2.050034)
			(end -0.5842 2.050034)
			(stroke
				(width 0.1524)
				(type default)
			)
			(layer "F.SilkS")
		)
		(fp_line
			(start -0.5842 -2.050034)
			(end -1.549908 -2.050034)
			(stroke
				(width 0.1524)
				(type default)
			)
			(layer "F.SilkS")
		)
		(fp_line
			(start 0 2.050034)
			(end 1.549908 2.050034)
			(stroke
				(width 0.1524)
				(type default)
			)
			(layer "F.SilkS")
		)
		(fp_line
			(start 1.549908 -2.050034)
			(end 0.5842 -2.050034)
			(stroke
				(width 0.1524)
				(type default)
			)
			(layer "F.SilkS")
		)
		(fp_line
			(start 1.549908 -1.9812)
			(end 1.549908 -2.050034)
			(stroke
				(width 0.1524)
				(type default)
			)
			(layer "F.SilkS")
		)
		(fp_line
			(start 1.549908 2.050034)
			(end 1.549908 1.9304)
			(stroke
				(width 0.1524)
				(type default)
			)
			(layer "F.SilkS")
		)
		(fp_poly
			(pts
				(xy -2.9464 -2.208022) (xy -2.9464 -1.192022) (xy -1.9304 -1.700022)
			)
			(stroke
				(width 0)
				(type default)
			)
			(fill yes)
			(layer "F.SilkS")
		)
		(fp_line
			(start -1.549908 -2.050034)
			(end -1.549908 2.050034)
			(stroke
				(width 0.1)
				(type default)
			)
			(layer "F.Fab")
		)
		(fp_line
			(start -1.549908 2.050034)
			(end 1.549908 2.050034)
			(stroke
				(width 0.1)
				(type default)
			)
			(layer "F.Fab")
		)
		(fp_line
			(start 1.549908 -2.050034)
			(end -1.549908 -2.050034)
			(stroke
				(width 0.1)
				(type default)
			)
			(layer "F.Fab")
		)
		(fp_line
			(start 1.549908 2.050034)
			(end 1.549908 -2.050034)
			(stroke
				(width 0.1)
				(type default)
			)
			(layer "F.Fab")
		)
		(fp_poly
			(pts
				(xy -2.9464 -2.208022) (xy -2.9464 -1.192022) (xy -1.9304 -1.700022)
			)
			(stroke
				(width 0)
				(type default)
			)
			(fill yes)
			(layer "F.Fab")
		)
		(pad "1" smd circle
			(at -1.35001 -1.700022)
			(size 0 0)
			(layers "F.Cu" "F.Mask" "F.Paste")
			(net "SW_P1V8_RETIMER_CPU0_BST")
		)
		(pad "2" smd rect
			(at -1.400048 -1.199896 90)
			(size 0.1778 0.8128)
			(layers "F.Cu" "F.Mask" "F.Paste")
			(net "GND")
		)
		(pad "3" smd rect
			(at -1.400048 -0.8001 90)
			(size 0.1778 0.8128)
			(layers "F.Cu" "F.Mask" "F.Paste")
			(net "P1V8_RETIMER_CPU0_CS")
		)
		(pad "4" smd rect
			(at -1.400048 -0.40005 90)
			(size 0.1778 0.8128)
			(layers "F.Cu" "F.Mask" "F.Paste")
			(net "P1V8_RETIMER_CPU0_MODE")
		)
		(pad "5" smd rect
			(at -1.400048 0 90)
			(size 0.1778 0.8128)
			(layers "F.Cu" "F.Mask" "F.Paste")
			(net "P1V8_RETIMER_CPU0_REF")
		)
		(pad "6" smd rect
			(at -1.400048 0.40005 90)
			(size 0.1778 0.8128)
			(layers "F.Cu" "F.Mask" "F.Paste")
			(net "GND")
		)
		(pad "7" smd rect
			(at -1.400048 0.8001 90)
			(size 0.1778 0.8128)
			(layers "F.Cu" "F.Mask" "F.Paste")
			(net "P1V8_RETIMER_CPU0_FB")
		)
		(pad "8" smd rect
			(at -1.400048 1.199896 90)
			(size 0.1778 0.8128)
			(layers "F.Cu" "F.Mask" "F.Paste")
			(net "P1V8_RETIMER_CPU0_EN")
		)
		(pad "9" smd rect
			(at -1.400048 1.700022 90)
			(size 0.3048 0.8128)
			(layers "F.Cu" "F.Mask" "F.Paste")
			(net "PWRGD_P1V8_RETIMER_CPU0")
		)
		(pad "10" smd rect
			(at -0.299974 1.299972)
			(size 0.3048 2.0066)
			(layers "F.Cu" "F.Mask" "F.Paste")
			(net "SW_P12V_AUX_P1V8_RETIMER_CPU0_FLT")
		)
		(pad "11_18" smd circle
			(at 1.175004 0.275082)
			(size 0 0)
			(layers "F.Cu" "F.Mask" "F.Paste")
			(net "GND")
		)
		(pad "19" smd rect
			(at 1.400048 -1.700022 270)
			(size 0.3048 0.8128)
			(layers "F.Cu" "F.Mask" "F.Paste")
			(net "P1V8_RETIMER_CPU0_VCC")
		)
		(pad "20" smd rect
			(at 0.299974 -1.299972)
			(size 0.3048 2.0066)
			(layers "F.Cu" "F.Mask" "F.Paste")
			(net "SW_P1V8_RETIMER_CPU0_SW")
		)
		(pad "21" smd rect
			(at -0.299974 -1.299972)
			(size 0.3048 2.0066)
			(layers "F.Cu" "F.Mask" "F.Paste")
			(net "SW_P12V_AUX_P1V8_RETIMER_CPU0_FLT")
		)
	)
	(footprint ""
		(layer "F.Cu")
		(at 177.81016 -390.2075)
		(property "Reference" "R1426"
			(at 0 0 0)
			(layer "F.SilkS")
			(hide yes)
			(effects
				(font
					(size 1.27 1.27)
				)
			)
		)
		(property "Value" ""
			(at 0 0 0)
			(layer "F.Fab")
			(effects
				(font
					(size 1.27 1.27)
				)
			)
		)
		(duplicate_pad_numbers_are_jumpers no)
		(fp_line
			(start -0.32512 -0.175006)
			(end 0.32512 -0.175006)
			(stroke
				(width 0.1)
				(type default)
			)
			(layer "F.Fab")
		)
		(fp_line
			(start -0.32512 0.175006)
			(end -0.32512 -0.175006)
			(stroke
				(width 0.1)
				(type default)
			)
			(layer "F.Fab")
		)
		(fp_line
			(start 0.32512 -0.175006)
			(end 0.32512 0.175006)
			(stroke
				(width 0.1)
				(type default)
			)
			(layer "F.Fab")
		)
		(fp_line
			(start 0.32512 0.175006)
			(end -0.32512 0.175006)
			(stroke
				(width 0.1)
				(type default)
			)
			(layer "F.Fab")
		)
		(pad "1" smd rect
			(at -0.2667 0)
			(size 0.3048 0.381)
			(layers "F.Cu" "F.Mask" "F.Paste")
			(net "P1V8_CPU1_RT_1D")
		)
		(pad "2" smd rect
			(at 0.2667 0 180)
			(size 0.3048 0.381)
			(layers "F.Cu" "F.Mask" "F.Paste")
			(net "RXDET_BYP_RT_CPU1_P2")
		)
	)
	(footprint ""
		(layer "F.Cu")
		(at 356.29596 -258.795012)
		(property "Reference" "C3899"
			(at 0 0 0)
			(layer "F.SilkS")
			(hide yes)
			(effects
				(font
					(size 1.27 1.27)
				)
			)
		)
		(property "Value" ""
			(at 0 0 0)
			(layer "F.Fab")
			(effects
				(font
					(size 1.27 1.27)
				)
			)
		)
		(duplicate_pad_numbers_are_jumpers no)
		(fp_line
			(start -0.7874 -0.4064)
			(end 0.7874 -0.4064)
			(stroke
				(width 0.1524)
				(type default)
			)
			(layer "F.SilkS")
		)
		(fp_line
			(start -0.7874 0.4064)
			(end -0.7874 -0.4064)
			(stroke
				(width 0.1524)
				(type default)
			)
			(layer "F.SilkS")
		)
		(fp_line
			(start 0.7874 -0.4064)
			(end 0.7874 0.4064)
			(stroke
				(width 0.1524)
				(type default)
			)
			(layer "F.SilkS")
		)
		(fp_line
			(start 0.7874 0.4064)
			(end -0.7874 0.4064)
			(stroke
				(width 0.1524)
				(type default)
			)
			(layer "F.SilkS")
		)
		(fp_line
			(start -0.67945 -0.305054)
			(end -0.12065 -0.305054)
			(stroke
				(width 0.1)
				(type default)
			)
			(layer "F.Fab")
		)
		(fp_line
			(start -0.67945 0.3048)
			(end -0.67945 -0.305054)
			(stroke
				(width 0.1)
				(type default)
			)
			(layer "F.Fab")
		)
		(fp_line
			(start -0.12065 -0.305054)
			(end -0.12065 -0.2794)
			(stroke
				(width 0.1)
				(type default)
			)
			(layer "F.Fab")
		)
		(fp_line
			(start -0.12065 -0.2794)
			(end 0.12065 -0.2794)
			(stroke
				(width 0.1)
				(type default)
			)
			(layer "F.Fab")
		)
		(fp_line
			(start -0.12065 0.2794)
			(end -0.12065 0.3048)
			(stroke
				(width 0.1)
				(type default)
			)
			(layer "F.Fab")
		)
		(fp_line
			(start -0.12065 0.3048)
			(end -0.67945 0.3048)
			(stroke
				(width 0.1)
				(type default)
			)
			(layer "F.Fab")
		)
		(fp_line
			(start 0.120396 0.2794)
			(end -0.12065 0.2794)
			(stroke
				(width 0.1)
				(type default)
			)
			(layer "F.Fab")
		)
		(fp_line
			(start 0.120396 0.3048)
			(end 0.120396 0.2794)
			(stroke
				(width 0.1)
				(type default)
			)
			(layer "F.Fab")
		)
		(fp_line
			(start 0.12065 -0.3048)
			(end 0.67945 -0.3048)
			(stroke
				(width 0.1)
				(type default)
			)
			(layer "F.Fab")
		)
		(fp_line
			(start 0.12065 -0.2794)
			(end 0.12065 -0.3048)
			(stroke
				(width 0.1)
				(type default)
			)
			(layer "F.Fab")
		)
		(fp_line
			(start 0.67945 -0.3048)
			(end 0.67945 0.3048)
			(stroke
				(width 0.1)
				(type default)
			)
			(layer "F.Fab")
		)
		(fp_line
			(start 0.67945 0.3048)
			(end 0.120396 0.3048)
			(stroke
				(width 0.1)
				(type default)
			)
			(layer "F.Fab")
		)
		(pad "1" smd circle
			(at -0.40005 0)
			(size 0 0)
			(layers "F.Cu" "F.Mask" "F.Paste")
			(net "PVDDIO_P0")
		)
		(pad "2" smd circle
			(at 0.40005 0)
			(size 0 0)
			(layers "F.Cu" "F.Mask" "F.Paste")
			(net "GND")
		)
	)
)
